(kicad_pcb
	(version 20260206)
	(generator "pcbnew")
	(generator_version "10.0")
	(general
		(thickness 1.6)
		(legacy_teardrops no)
	)
	(paper "A4")
	(title_block
		(title "Wiwynn_Tioga_Pass_MB.brd")
		(comment 1 "Tioga Pass / footprints 4403-4409 of 4770")
	)
	(layers
		(0 "F.Cu" signal "TOP")
		(4 "In1.Cu" signal "L2GND")
		(6 "In2.Cu" signal "L3")
		(8 "In3.Cu" signal "L4GND")
		(10 "In4.Cu" signal "L5")
		(12 "In5.Cu" signal "L6GND")
		(14 "In6.Cu" signal "L7VCC")
		(16 "In7.Cu" signal "L8VCC")
		(18 "In8.Cu" signal "L9GND")
		(20 "In9.Cu" signal "L10")
		(22 "In10.Cu" signal "L11GND")
		(24 "In11.Cu" signal "L12")
		(26 "In12.Cu" signal "L13GND")
		(2 "B.Cu" signal "BOTTOM")
		(9 "F.Adhes" user "F.Adhesive")
		(11 "B.Adhes" user "B.Adhesive")
		(13 "F.Paste" user "Package Geometry/Pastemask Top")
		(15 "B.Paste" user "Package Geometry/Pastemask Bottom")
		(5 "F.SilkS" user "Ref Des/Silkscreen Top")
		(7 "B.SilkS" user "Ref Des/Silkscreen Bottom")
		(1 "F.Mask" user "Board Geometry/Soldermask Top")
		(3 "B.Mask" user "Board Geometry/Soldermask Bottom")
		(17 "Dwgs.User" user "User.Drawings")
		(19 "Cmts.User" user "User.Comments")
		(21 "Eco1.User" user "User.Eco1")
		(23 "Eco2.User" user "User.Eco2")
		(25 "Edge.Cuts" user "Board Geometry/Outline")
		(27 "Margin" user)
		(31 "F.CrtYd" user "Package Geometry/Place Bound Top")
		(29 "B.CrtYd" user "Package Geometry/Place Bound Bottom")
		(35 "F.Fab" user "Ref Des/Assembly Top")
		(33 "B.Fab" user "Ref Des/Assembly Bottom")
	)
	(footprint ""
		(layer "B.Cu")
		(at 370.1669 -104.8766 90)
		(property "Reference" "C3N27"
			(at 0 0 90)
			(layer "B.SilkS")
			(hide yes)
			(effects
				(font
					(size 1.27 1.27)
				)
				(justify mirror)
			)
		)
		(property "Value" ""
			(at 0 0 90)
			(layer "B.Fab")
			(effects
				(font
					(size 1.27 1.27)
				)
				(justify mirror)
			)
		)
		(duplicate_pad_numbers_are_jumpers no)
		(fp_poly
			(pts
				(xy 0.4953 -0.2032) (xy -0.4953 -0.2032) (xy -0.4953 1.6002) (xy 0.4953 1.6002)
			)
			(stroke
				(width 0)
				(type default)
			)
			(fill no)
			(layer "B.CrtYd")
		)
		(fp_line
			(start 0.4953 -0.2032)
			(end -0.4953 -0.2032)
			(stroke
				(width 0.1)
				(type default)
			)
			(layer "B.Fab")
		)
		(fp_line
			(start -0.4953 -0.2032)
			(end -0.4953 1.6002)
			(stroke
				(width 0.1)
				(type default)
			)
			(layer "B.Fab")
		)
		(fp_line
			(start 0.4953 1.6002)
			(end 0.4953 -0.2032)
			(stroke
				(width 0.1)
				(type default)
			)
			(layer "B.Fab")
		)
		(fp_line
			(start -0.4953 1.6002)
			(end 0.4953 1.6002)
			(stroke
				(width 0.1)
				(type default)
			)
			(layer "B.Fab")
		)
		(pad "1" smd rect
			(at 0 0 270)
			(size 0.762 0.889)
			(layers "B.Cu" "B.Mask" "B.Paste")
			(net "PVNN_PCH_STBY")
		)
		(pad "2" smd rect
			(at 0 1.397 270)
			(size 0.762 0.889)
			(layers "B.Cu" "B.Mask" "B.Paste")
			(net "GND")
		)
		(zone
			(layer "B.Cu")
			(hatch none 0.5)
			(connect_pads
				(clearance 0)
			)
			(min_thickness 0.25)
			(keepout
				(tracks not_allowed)
				(vias allowed)
				(pads allowed)
				(copperpour not_allowed)
				(footprints allowed)
			)
			(placement
				(enabled no)
				(sheetname "")
			)
			(fill
				(thermal_gap 0.5)
				(thermal_bridge_width 0.5)
				(island_removal_mode 0)
			)
			(polygon
				(pts
					(xy 370.6114 -105.2576) (xy 370.6114 -104.4956) (xy 371.1194 -104.4956) (xy 371.1194 -105.2576)
				)
			)
		)
	)
	(footprint ""
		(layer "B.Cu")
		(at 446.9892 -17.3482 90)
		(property "Reference" "R3W7"
			(at 0.8382 -0.67818 90)
			(unlocked yes)
			(layer "B.SilkS")
			(effects
				(font
					(size 0.4064 0.254)
					(thickness 0.1524)
				)
				(justify left mirror)
			)
		)
		(property "Value" ""
			(at 0 0 90)
			(layer "B.Fab")
			(effects
				(font
					(size 1.27 1.27)
				)
				(justify mirror)
			)
		)
		(duplicate_pad_numbers_are_jumpers no)
		(fp_poly
			(pts
				(xy 0.2794 -0.1016) (xy -0.2794 -0.1016) (xy -0.2794 0.9906) (xy 0.2794 0.9906)
			)
			(stroke
				(width 0)
				(type default)
			)
			(fill no)
			(layer "B.CrtYd")
		)
		(fp_line
			(start 0.2794 -0.1016)
			(end 0.2794 0.9906)
			(stroke
				(width 0.1)
				(type default)
			)
			(layer "B.Fab")
		)
		(fp_line
			(start -0.2794 -0.1016)
			(end 0.2794 -0.1016)
			(stroke
				(width 0.1)
				(type default)
			)
			(layer "B.Fab")
		)
		(fp_line
			(start 0.2794 0.9906)
			(end -0.2794 0.9906)
			(stroke
				(width 0.1)
				(type default)
			)
			(layer "B.Fab")
		)
		(fp_line
			(start -0.2794 0.9906)
			(end -0.2794 -0.1016)
			(stroke
				(width 0.1)
				(type default)
			)
			(layer "B.Fab")
		)
		(pad "1" smd rect
			(at 0 0 270)
			(size 0.508 0.508)
			(layers "B.Cu" "B.Mask" "B.Paste")
			(net "P3V3_STBY")
		)
		(pad "2" smd rect
			(at 0 0.889 270)
			(size 0.508 0.508)
			(layers "B.Cu" "B.Mask" "B.Paste")
			(net "VREF_2V2")
		)
		(zone
			(layer "B.Cu")
			(hatch none 0.5)
			(connect_pads
				(clearance 0)
			)
			(min_thickness 0.25)
			(keepout
				(tracks allowed)
				(vias not_allowed)
				(pads allowed)
				(copperpour not_allowed)
				(footprints allowed)
			)
			(placement
				(enabled no)
				(sheetname "")
			)
			(fill
				(thermal_gap 0.5)
				(thermal_bridge_width 0.5)
				(island_removal_mode 0)
			)
			(polygon
				(pts
					(xy 447.2432 -17.6022) (xy 447.2432 -17.0942) (xy 447.6242 -17.0942) (xy 447.6242 -17.6022)
				)
			)
		)
		(zone
			(layer "B.Cu")
			(hatch none 0.5)
			(connect_pads
				(clearance 0)
			)
			(min_thickness 0.25)
			(keepout
				(tracks not_allowed)
				(vias allowed)
				(pads allowed)
				(copperpour not_allowed)
				(footprints allowed)
			)
			(placement
				(enabled no)
				(sheetname "")
			)
			(fill
				(thermal_gap 0.5)
				(thermal_bridge_width 0.5)
				(island_removal_mode 0)
			)
			(polygon
				(pts
					(xy 447.6242 -17.6022) (xy 447.6242 -17.0942) (xy 447.2432 -17.0942) (xy 447.2432 -17.6022)
				)
			)
		)
	)
	(footprint ""
		(layer "B.Cu")
		(at 411.324552 -29.55036 90)
		(property "Reference" "C25W68"
			(at 0.8382 -0.67818 90)
			(unlocked yes)
			(layer "B.SilkS")
			(effects
				(font
					(size 0.4064 0.254)
					(thickness 0.1524)
				)
				(justify left mirror)
			)
		)
		(property "Value" ""
			(at 0 0 90)
			(layer "B.Fab")
			(effects
				(font
					(size 1.27 1.27)
				)
				(justify mirror)
			)
		)
		(duplicate_pad_numbers_are_jumpers no)
		(fp_poly
			(pts
				(xy -0.3048 -0.1016) (xy -0.3048 0.9906) (xy 0.3048 0.9906) (xy 0.3048 -0.1016)
			)
			(stroke
				(width 0)
				(type default)
			)
			(fill no)
			(layer "B.CrtYd")
		)
		(fp_line
			(start 0.3048 -0.1016)
			(end 0.3048 0.9906)
			(stroke
				(width 0.1)
				(type default)
			)
			(layer "B.Fab")
		)
		(fp_line
			(start -0.3048 -0.1016)
			(end 0.3048 -0.1016)
			(stroke
				(width 0.1)
				(type default)
			)
			(layer "B.Fab")
		)
		(fp_line
			(start 0.3048 0.9906)
			(end -0.3048 0.9906)
			(stroke
				(width 0.1)
				(type default)
			)
			(layer "B.Fab")
		)
		(fp_line
			(start -0.3048 0.9906)
			(end -0.3048 -0.1016)
			(stroke
				(width 0.1)
				(type default)
			)
			(layer "B.Fab")
		)
		(pad "1" smd rect
			(at 0 0 270)
			(size 0.508 0.508)
			(layers "B.Cu" "B.Mask" "B.Paste")
			(net "VCC_VA_3V3")
		)
		(pad "2" smd rect
			(at 0 0.889 270)
			(size 0.508 0.508)
			(layers "B.Cu" "B.Mask" "B.Paste")
			(net "GND")
		)
		(zone
			(layer "B.Cu")
			(hatch none 0.5)
			(connect_pads
				(clearance 0)
			)
			(min_thickness 0.25)
			(keepout
				(tracks allowed)
				(vias not_allowed)
				(pads allowed)
				(copperpour not_allowed)
				(footprints allowed)
			)
			(placement
				(enabled no)
				(sheetname "")
			)
			(fill
				(thermal_gap 0.5)
				(thermal_bridge_width 0.5)
				(island_removal_mode 0)
			)
			(polygon
				(pts
					(xy 411.578552 -29.80436) (xy 411.578552 -29.29636) (xy 411.959552 -29.29636) (xy 411.959552 -29.80436)
				)
			)
		)
		(zone
			(layer "B.Cu")
			(hatch none 0.5)
			(connect_pads
				(clearance 0)
			)
			(min_thickness 0.25)
			(keepout
				(tracks not_allowed)
				(vias allowed)
				(pads allowed)
				(copperpour not_allowed)
				(footprints allowed)
			)
			(placement
				(enabled no)
				(sheetname "")
			)
			(fill
				(thermal_gap 0.5)
				(thermal_bridge_width 0.5)
				(island_removal_mode 0)
			)
			(polygon
				(pts
					(xy 411.959552 -29.80436) (xy 411.959552 -29.29636) (xy 411.578552 -29.29636) (xy 411.578552 -29.80436)
				)
			)
		)
	)
	(footprint ""
		(layer "B.Cu")
		(at 390.93775 -113.45545)
		(property "Reference" "C2M21"
			(at 0 0 0)
			(layer "B.SilkS")
			(hide yes)
			(effects
				(font
					(size 1.27 1.27)
				)
				(justify mirror)
			)
		)
		(property "Value" ""
			(at 0 0 0)
			(layer "B.Fab")
			(effects
				(font
					(size 1.27 1.27)
				)
				(justify mirror)
			)
		)
		(duplicate_pad_numbers_are_jumpers no)
		(fp_rect
			(start 0.2794 0.9144)
			(end -0.2794 -0.1143)
			(stroke
				(width 0)
				(type default)
			)
			(fill no)
			(layer "B.CrtYd")
		)
		(fp_line
			(start -0.2794 -0.1143)
			(end -0.2794 0.9144)
			(stroke
				(width 0.1)
				(type default)
			)
			(layer "B.Fab")
		)
		(fp_line
			(start -0.2794 0.9144)
			(end 0.2794 0.9144)
			(stroke
				(width 0.1)
				(type default)
			)
			(layer "B.Fab")
		)
		(fp_line
			(start 0.2794 -0.1143)
			(end -0.2794 -0.1143)
			(stroke
				(width 0.1)
				(type default)
			)
			(layer "B.Fab")
		)
		(fp_line
			(start 0.2794 0.9144)
			(end 0.2794 -0.1143)
			(stroke
				(width 0.1)
				(type default)
			)
			(layer "B.Fab")
		)
		(pad "1" smd custom
			(at 0 0 270)
			(size 0.10414 0.10414)
			(layers "B.Cu" "B.Mask" "B.Paste")
			(net "P1V05_PCH_STBY")
			(options
				(clearance outline)
				(anchor circle)
			)
			(primitives
				(gr_poly
					(pts
						(xy -0.20828 -0.08636) (xy -0.20828 0.08636) (xy -0.08636 0.20828) (xy 0.086614 0.20828) (xy 0.20828 0.086614)
						(xy 0.20828 -0.08636) (xy 0.08636 -0.20828) (xy -0.08636 -0.20828)
					)
					(width 0)
					(fill yes)
				)
			)
		)
		(pad "2" smd custom
			(at 0 0.8001 270)
			(size 0.10414 0.10414)
			(layers "B.Cu" "B.Mask" "B.Paste")
			(net "GND")
			(options
				(clearance outline)
				(anchor circle)
			)
			(primitives
				(gr_poly
					(pts
						(xy -0.20828 -0.08636) (xy -0.20828 0.08636) (xy -0.08636 0.20828) (xy 0.086614 0.20828) (xy 0.20828 0.086614)
						(xy 0.20828 -0.08636) (xy 0.08636 -0.20828) (xy -0.08636 -0.20828)
					)
					(width 0)
					(fill yes)
				)
			)
		)
		(zone
			(layer "B.Cu")
			(hatch none 0.5)
			(connect_pads
				(clearance 0)
			)
			(min_thickness 0.25)
			(keepout
				(tracks not_allowed)
				(vias allowed)
				(pads allowed)
				(copperpour not_allowed)
				(footprints allowed)
			)
			(placement
				(enabled no)
				(sheetname "")
			)
			(fill
				(thermal_gap 0.5)
				(thermal_bridge_width 0.5)
				(island_removal_mode 0)
			)
			(polygon
				(pts
					(xy 391.02538 -113.2459) (xy 391.02538 -112.8649) (xy 390.85012 -112.8649) (xy 390.849866 -113.2459)
				)
			)
		)
		(zone
			(layer "B.Cu")
			(hatch none 0.5)
			(connect_pads
				(clearance 0)
			)
			(min_thickness 0.25)
			(keepout
				(tracks allowed)
				(vias not_allowed)
				(pads allowed)
				(copperpour not_allowed)
				(footprints allowed)
			)
			(placement
				(enabled no)
				(sheetname "")
			)
			(fill
				(thermal_gap 0.5)
				(thermal_bridge_width 0.5)
				(island_removal_mode 0)
			)
			(polygon
				(pts
					(xy 391.02538 -113.2459) (xy 391.02538 -112.8649) (xy 390.85012 -112.8649) (xy 390.849866 -113.2459)
				)
			)
		)
	)
	(footprint ""
		(layer "B.Cu")
		(at 402.043646 -24.838152)
		(property "Reference" "R1U44"
			(at 0 0 0)
			(layer "B.SilkS")
			(hide yes)
			(effects
				(font
					(size 1.27 1.27)
				)
				(justify mirror)
			)
		)
		(property "Value" "*"
			(at -0.064008 -4.108196 0)
			(unlocked yes)
			(layer "B.Fab")
			(hide yes)
			(effects
				(font
					(size 1.27 1.016)
					(thickness 0.1524)
				)
				(justify mirror)
			)
		)
		(property "Device Type" "1K82R2F-1-GP_SMD-RG-1K82R2F-1-A"
			(at -0.064008 -5.632196 0)
			(unlocked yes)
			(layer "B.Fab")
			(hide yes)
			(effects
				(font
					(size 1.27 1.016)
					(thickness 0.1524)
				)
				(justify mirror)
			)
		)
		(duplicate_pad_numbers_are_jumpers no)
		(fp_line
			(start -0.508 -0.9398)
			(end 0.508 -0.9398)
			(stroke
				(width 0.1524)
				(type default)
			)
			(layer "B.SilkS")
		)
		(fp_line
			(start 0.508 -0.9398)
			(end 0.508 0.9398)
			(stroke
				(width 0.1524)
				(type default)
			)
			(layer "B.SilkS")
		)
		(fp_rect
			(start 0.508 0.9398)
			(end -0.508 -0.9398)
			(stroke
				(width 0)
				(type default)
			)
			(fill no)
			(layer "B.CrtYd")
		)
		(fp_rect
			(start 0.508 0.9398)
			(end -0.508 -0.9398)
			(stroke
				(width 0)
				(type default)
			)
			(fill no)
			(layer "B.Fab")
		)
		(pad "1" smd custom
			(at 0 -0.4445 180)
			(size 0.1397 0.1397)
			(layers "B.Cu" "B.Mask" "B.Paste")
			(net "A_P5V_STBY_SCALED")
			(options
				(clearance outline)
				(anchor circle)
			)
			(primitives
				(gr_poly
					(pts
						(arc
							(start -0.1778 0.2794)
							(mid -0.249642 0.249642)
							(end -0.2794 0.1778)
						)
						(arc
							(start -0.2794 -0.1778)
							(mid -0.249642 -0.249642)
							(end -0.1778 -0.2794)
						)
						(arc
							(start 0.1778 -0.2794)
							(mid 0.249642 -0.249642)
							(end 0.2794 -0.1778)
						)
						(arc
							(start 0.2794 0.1778)
							(mid 0.249642 0.249642)
							(end 0.1778 0.2794)
						)
					)
					(width 0)
					(fill yes)
				)
			)
		)
		(pad "2" smd custom
			(at 0 0.4445 180)
			(size 0.1397 0.1397)
			(layers "B.Cu" "B.Mask" "B.Paste")
			(net "GND")
			(options
				(clearance outline)
				(anchor circle)
			)
			(primitives
				(gr_poly
					(pts
						(arc
							(start -0.1778 0.2794)
							(mid -0.249642 0.249642)
							(end -0.2794 0.1778)
						)
						(arc
							(start -0.2794 -0.1778)
							(mid -0.249642 -0.249642)
							(end -0.1778 -0.2794)
						)
						(arc
							(start 0.1778 -0.2794)
							(mid 0.249642 -0.249642)
							(end 0.2794 -0.1778)
						)
						(arc
							(start 0.2794 0.1778)
							(mid 0.249642 0.249642)
							(end 0.1778 0.2794)
						)
					)
					(width 0)
					(fill yes)
				)
			)
		)
	)
	(footprint ""
		(layer "B.Cu")
		(at 448.19189 -28.8036 -90)
		(property "Reference" "C25W10"
			(at 0.8382 -0.67818 270)
			(unlocked yes)
			(layer "B.SilkS")
			(effects
				(font
					(size 0.4064 0.254)
					(thickness 0.1524)
				)
				(justify left mirror)
			)
		)
		(property "Value" ""
			(at 0 0 90)
			(layer "B.Fab")
			(effects
				(font
					(size 1.27 1.27)
				)
				(justify mirror)
			)
		)
		(duplicate_pad_numbers_are_jumpers no)
		(fp_poly
			(pts
				(xy -0.3048 -0.1016) (xy -0.3048 0.9906) (xy 0.3048 0.9906) (xy 0.3048 -0.1016)
			)
			(stroke
				(width 0)
				(type default)
			)
			(fill no)
			(layer "B.CrtYd")
		)
		(fp_line
			(start -0.3048 0.9906)
			(end -0.3048 -0.1016)
			(stroke
				(width 0.1)
				(type default)
			)
			(layer "B.Fab")
		)
		(fp_line
			(start 0.3048 0.9906)
			(end -0.3048 0.9906)
			(stroke
				(width 0.1)
				(type default)
			)
			(layer "B.Fab")
		)
		(fp_line
			(start -0.3048 -0.1016)
			(end 0.3048 -0.1016)
			(stroke
				(width 0.1)
				(type default)
			)
			(layer "B.Fab")
		)
		(fp_line
			(start 0.3048 -0.1016)
			(end 0.3048 0.9906)
			(stroke
				(width 0.1)
				(type default)
			)
			(layer "B.Fab")
		)
		(pad "1" smd rect
			(at 0 0 90)
			(size 0.508 0.508)
			(layers "B.Cu" "B.Mask" "B.Paste")
			(net "P1V2_AUX_BMC")
		)
		(pad "2" smd rect
			(at 0 0.889 90)
			(size 0.508 0.508)
			(layers "B.Cu" "B.Mask" "B.Paste")
			(net "BMC_M_VREFCA")
		)
		(zone
			(layer "B.Cu")
			(hatch none 0.5)
			(connect_pads
				(clearance 0)
			)
			(min_thickness 0.25)
			(keepout
				(tracks not_allowed)
				(vias allowed)
				(pads allowed)
				(copperpour not_allowed)
				(footprints allowed)
			)
			(placement
				(enabled no)
				(sheetname "")
			)
			(fill
				(thermal_gap 0.5)
				(thermal_bridge_width 0.5)
				(island_removal_mode 0)
			)
			(polygon
				(pts
					(xy 447.55689 -28.5496) (xy 447.55689 -29.0576) (xy 447.93789 -29.0576) (xy 447.93789 -28.5496)
				)
			)
		)
		(zone
			(layer "B.Cu")
			(hatch none 0.5)
			(connect_pads
				(clearance 0)
			)
			(min_thickness 0.25)
			(keepout
				(tracks allowed)
				(vias not_allowed)
				(pads allowed)
				(copperpour not_allowed)
				(footprints allowed)
			)
			(placement
				(enabled no)
				(sheetname "")
			)
			(fill
				(thermal_gap 0.5)
				(thermal_bridge_width 0.5)
				(island_removal_mode 0)
			)
			(polygon
				(pts
					(xy 447.93789 -28.5496) (xy 447.93789 -29.0576) (xy 447.55689 -29.0576) (xy 447.55689 -28.5496)
				)
			)
		)
	)
	(footprint ""
		(layer "B.Cu")
		(at 408.1907 -14.7828 -90)
		(property "Reference" "R2R10"
			(at 0 0 90)
			(layer "B.SilkS")
			(hide yes)
			(effects
				(font
					(size 1.27 1.27)
				)
				(justify mirror)
			)
		)
		(property "Value" ""
			(at 0 0 90)
			(layer "B.Fab")
			(effects
				(font
					(size 1.27 1.27)
				)
				(justify mirror)
			)
		)
		(duplicate_pad_numbers_are_jumpers no)
		(fp_poly
			(pts
				(xy 0.2794 -0.1016) (xy -0.2794 -0.1016) (xy -0.2794 0.9906) (xy 0.2794 0.9906)
			)
			(stroke
				(width 0)
				(type default)
			)
			(fill no)
			(layer "B.CrtYd")
		)
		(fp_line
			(start -0.2794 0.9906)
			(end -0.2794 -0.1016)
			(stroke
				(width 0.1)
				(type default)
			)
			(layer "B.Fab")
		)
		(fp_line
			(start 0.2794 0.9906)
			(end -0.2794 0.9906)
			(stroke
				(width 0.1)
				(type default)
			)
			(layer "B.Fab")
		)
		(fp_line
			(start -0.2794 -0.1016)
			(end 0.2794 -0.1016)
			(stroke
				(width 0.1)
				(type default)
			)
			(layer "B.Fab")
		)
		(fp_line
			(start 0.2794 -0.1016)
			(end 0.2794 0.9906)
			(stroke
				(width 0.1)
				(type default)
			)
			(layer "B.Fab")
		)
		(pad "1" smd rect
			(at 0 0 90)
			(size 0.508 0.508)
			(layers "B.Cu" "B.Mask" "B.Paste")
			(net "FP_NMI_BTN_R_N")
		)
		(pad "2" smd rect
			(at 0 0.889 90)
			(size 0.508 0.508)
			(layers "B.Cu" "B.Mask" "B.Paste")
			(net "FP_NMI_BTN_N")
		)
		(zone
			(layer "B.Cu")
			(hatch none 0.5)
			(connect_pads
				(clearance 0)
			)
			(min_thickness 0.25)
			(keepout
				(tracks not_allowed)
				(vias allowed)
				(pads allowed)
				(copperpour not_allowed)
				(footprints allowed)
			)
			(placement
				(enabled no)
				(sheetname "")
			)
			(fill
				(thermal_gap 0.5)
				(thermal_bridge_width 0.5)
				(island_removal_mode 0)
			)
			(polygon
				(pts
					(xy 407.5557 -14.5288) (xy 407.5557 -15.0368) (xy 407.9367 -15.0368) (xy 407.9367 -14.5288)
				)
			)
		)
		(zone
			(layer "B.Cu")
			(hatch none 0.5)
			(connect_pads
				(clearance 0)
			)
			(min_thickness 0.25)
			(keepout
				(tracks allowed)
				(vias not_allowed)
				(pads allowed)
				(copperpour not_allowed)
				(footprints allowed)
			)
			(placement
				(enabled no)
				(sheetname "")
			)
			(fill
				(thermal_gap 0.5)
				(thermal_bridge_width 0.5)
				(island_removal_mode 0)
			)
			(polygon
				(pts
					(xy 407.9367 -14.5288) (xy 407.9367 -15.0368) (xy 407.5557 -15.0368) (xy 407.5557 -14.5288)
				)
			)
		)
	)
)
